# TIMECARD (Time Appliance Project (Time Card)) — schematic netlist excerpt (pin names and nets, part order shuffled) for the footprints in the layout excerpt that follows; sources: Cadence DE-HDL packaged netlist, KiCad conversion of R4006-B0001-02_R01.brd

ME10  MEC_MTH8  pkg MTH125C236N_V8  page 34
  \1\  = SG
  \2\  = SG
  \3\  = SG
  \4\  = SG
  \5\  = SG
  \6\  = SG
  \7\  = SG
  \8\  = SG

(kicad_pcb
	(version 20260206)
	(generator "pcbnew")
	(generator_version "10.0")
	(general
		(thickness 1.6)
		(legacy_teardrops no)
	)
	(paper "A4")
	(title_block
		(title "timecard-production-celestica-r4006 — R4006-B0001-02_R01.brd")
		(comment 1 "Time Appliance Project (Time Card) / footprints 88-88 of 1113")
	)
	(layers
		(0 "F.Cu" signal "TOP")
		(4 "In1.Cu" signal "L02_GND1")
		(6 "In2.Cu" signal "L03_SIG1")
		(8 "In3.Cu" signal "L04_GND2")
		(10 "In4.Cu" signal "L05_VCC1")
		(12 "In5.Cu" signal "L06_VCC2")
		(14 "In6.Cu" signal "L07_GND3")
		(16 "In7.Cu" signal "L08_SIG2")
		(18 "In8.Cu" signal "L09_GND4")
		(2 "B.Cu" signal "BOTTOM")
		(9 "F.Adhes" user "F.Adhesive")
		(11 "B.Adhes" user "B.Adhesive")
		(13 "F.Paste" user "Package Geometry/Pastemask Top")
		(15 "B.Paste" user "Package Geometry/Pastemask Bottom")
		(5 "F.SilkS" user "Ref Des/Silkscreen Top")
		(7 "B.SilkS" user "Ref Des/Silkscreen Bottom")
		(1 "F.Mask" user "Board Geometry/Soldermask Top")
		(3 "B.Mask" user "Board Geometry/Soldermask Bottom")
		(17 "Dwgs.User" user "User.Drawings")
		(19 "Cmts.User" user "User.Comments")
		(21 "Eco1.User" user "User.Eco1")
		(23 "Eco2.User" user "User.Eco2")
		(25 "Edge.Cuts" user "Board Geometry/Outline")
		(27 "Margin" user)
		(31 "F.CrtYd" user "Package Geometry/Place Bound Top")
		(29 "B.CrtYd" user "Package Geometry/Place Bound Bottom")
		(35 "F.Fab" user "Ref Des/Assembly Top")
		(33 "B.Fab" user "Ref Des/Assembly Bottom")
	)
	(footprint ""
		(layer "F.Cu")
		(at 7.500112 -9.349994)
		(property "Reference" "ME10"
			(at -4.325112 2.531364 0)
			(unlocked yes)
			(layer "F.SilkS")
			(effects
				(font
					(size 0.7874 0.5842)
					(thickness 0.1524)
				)
			)
		)
		(property "Value" ""
			(at 0 0 0)
			(layer "F.Fab")
			(effects
				(font
					(size 1.27 1.27)
				)
			)
		)
		(property "Device Type" "MEC_MTH8-MTH125C236N_V8-MTH125A"
			(at 0 5.08127 0)
			(unlocked yes)
			(layer "F.Fab")
			(hide yes)
			(effects
				(font
					(size 0.7874 0.5842)
					(thickness 0.1524)
				)
			)
		)
		(duplicate_pad_numbers_are_jumpers no)
		(fp_poly
			(pts
				(arc
					(start 3.5052 0)
					(mid -3.5052 0)
					(end 3.5052 0)
				)
			)
			(stroke
				(width 0)
				(type default)
			)
			(fill no)
			(layer "B.CrtYd")
		)
		(fp_poly
			(pts
				(arc
					(start 3.5052 0)
					(mid -3.5052 0)
					(end 3.5052 0)
				)
			)
			(stroke
				(width 0)
				(type default)
			)
			(fill no)
			(layer "F.CrtYd")
		)
		(fp_circle
			(center 0 0)
			(end 2.9972 0)
			(stroke
				(width 0.1)
				(type default)
			)
			(fill no)
			(layer "B.Fab")
		)
		(fp_circle
			(center 0 0)
			(end 2.9972 0)
			(stroke
				(width 0.1)
				(type default)
			)
			(fill no)
			(layer "F.Fab")
		)
		(pad "" np_thru_hole circle
			(at 0 0)
			(size 2.921 2.921)
			(drill 3.175)
			(layers "*.Cu" "*.Mask")
			(padstack
				(mode front_inner_back)
				(layer "Inner"
					(shape circle)
					(size 2.921 2.921)
					(clearance 0.4445)
				)
				(layer "B.Cu"
					(shape circle)
					(size 2.921 2.921)
				)
			)
		)
		(pad "1" thru_hole circle
			(at 0 -2.4511)
			(size 0.6096 0.6096)
			(drill 0.3048)
			(layers "*.Cu" "*.Mask")
			(remove_unused_layers no)
			(net "SG")
			(padstack
				(mode front_inner_back)
				(layer "Inner"
					(shape circle)
					(size 0.6096 0.6096)
					(clearance 0.1143)
				)
				(layer "B.Cu"
					(shape circle)
					(size 0.6096 0.6096)
				)
			)
		)
		(pad "2" thru_hole circle
			(at 1.733296 -1.733296)
			(size 0.6096 0.6096)
			(drill 0.3048)
			(layers "*.Cu" "*.Mask")
			(remove_unused_layers no)
			(net "SG")
			(padstack
				(mode front_inner_back)
				(layer "Inner"
					(shape circle)
					(size 0.6096 0.6096)
					(clearance 0.1143)
				)
				(layer "B.Cu"
					(shape circle)
					(size 0.6096 0.6096)
				)
			)
		)
		(pad "3" thru_hole circle
			(at 2.4511 0)
			(size 0.6096 0.6096)
			(drill 0.3048)
			(layers "*.Cu" "*.Mask")
			(remove_unused_layers no)
			(net "SG")
			(padstack
				(mode front_inner_back)
				(layer "Inner"
					(shape circle)
					(size 0.6096 0.6096)
					(clearance 0.1143)
				)
				(layer "B.Cu"
					(shape circle)
					(size 0.6096 0.6096)
				)
			)
		)
		(pad "4" thru_hole circle
			(at 1.733296 1.733296)
			(size 0.6096 0.6096)
			(drill 0.3048)
			(layers "*.Cu" "*.Mask")
			(remove_unused_layers no)
			(net "SG")
			(padstack
				(mode front_inner_back)
				(layer "Inner"
					(shape circle)
					(size 0.6096 0.6096)
					(clearance 0.1143)
				)
				(layer "B.Cu"
					(shape circle)
					(size 0.6096 0.6096)
				)
			)
		)
		(pad "5" thru_hole circle
			(at 0 2.4511)
			(size 0.6096 0.6096)
			(drill 0.3048)
			(layers "*.Cu" "*.Mask")
			(remove_unused_layers no)
			(net "SG")
			(padstack
				(mode front_inner_back)
				(layer "Inner"
					(shape circle)
					(size 0.6096 0.6096)
					(clearance 0.1143)
				)
				(layer "B.Cu"
					(shape circle)
					(size 0.6096 0.6096)
				)
			)
		)
		(pad "6" thru_hole circle
			(at -1.733296 1.733296)
			(size 0.6096 0.6096)
			(drill 0.3048)
			(layers "*.Cu" "*.Mask")
			(remove_unused_layers no)
			(net "SG")
			(padstack
				(mode front_inner_back)
				(layer "Inner"
					(shape circle)
					(size 0.6096 0.6096)
					(clearance 0.1143)
				)
				(layer "B.Cu"
					(shape circle)
					(size 0.6096 0.6096)
				)
			)
		)
		(pad "7" thru_hole circle
			(at -2.4511 0)
			(size 0.6096 0.6096)
			(drill 0.3048)
			(layers "*.Cu" "*.Mask")
			(remove_unused_layers no)
			(net "SG")
			(padstack
				(mode front_inner_back)
				(layer "Inner"
					(shape circle)
					(size 0.6096 0.6096)
					(clearance 0.1143)
				)
				(layer "B.Cu"
					(shape circle)
					(size 0.6096 0.6096)
				)
			)
		)
		(pad "8" thru_hole circle
			(at -1.733296 -1.733296)
			(size 0.6096 0.6096)
			(drill 0.3048)
			(layers "*.Cu" "*.Mask")
			(remove_unused_layers no)
			(net "SG")
			(padstack
				(mode front_inner_back)
				(layer "Inner"
					(shape circle)
					(size 0.6096 0.6096)
					(clearance 0.1143)
				)
				(layer "B.Cu"
					(shape circle)
					(size 0.6096 0.6096)
				)
			)
		)
		(zone
			(layers "F.Cu" "B.Cu" "In1.Cu" "In2.Cu" "In3.Cu" "In4.Cu" "In5.Cu" "In6.Cu"
				"In7.Cu" "In8.Cu"
			)
			(hatch none 0.5)
			(connect_pads
				(clearance 0)
			)
			(min_thickness 0.25)
			(keepout
				(tracks not_allowed)
				(vias allowed)
				(pads allowed)
				(copperpour not_allowed)
				(footprints allowed)
			)
			(placement
				(enabled no)
				(sheetname "")
			)
			(fill
				(thermal_gap 0.5)
				(thermal_bridge_width 0.5)
				(island_removal_mode 0)
			)
			(polygon
				(pts
					(arc
						(start 9.392412 -9.349994)
						(mid 5.607812 -9.349994)
						(end 9.392412 -9.349994)
					)
				)
			)
		)
	)
)
